# SCM (Grand Teton) — schematic netlist excerpt (pin names and nets, part order shuffled) for the footprints in the layout excerpt that follows; sources: Cadence DE-HDL packaged netlist, KiCad conversion of 12092022_DA0F0TMDCD0_F0T_Management_Board_D_brd_V3_OCP.brd

R482  Q_RES  33.2 1% CHIP  pkg 0402LF  page 45 : A = SPI_PCH_MUXED_IO0 ; B = SPI_PCH_IO0_FLASH_R1
R574  Q_RES  0 5% CHIP  pkg 0402LF  page 35 : A = SMB_BMC_ALERT16_N ; B = SMB_BMC_ALERT16_R2_N

(kicad_pcb
	(version 20260206)
	(generator "pcbnew")
	(generator_version "10.0")
	(general
		(thickness 1.6)
		(legacy_teardrops no)
	)
	(paper "A4")
	(title_block
		(title "12092022_DA0F0TMDCD0_F0T_Management_Board_D_brd_V3_OCP.brd")
		(comment 1 "Grand Teton / footprints 75-76 of 1440")
	)
	(layers
		(0 "F.Cu" signal "TOP")
		(4 "In1.Cu" signal "GND")
		(6 "In2.Cu" signal "IN1")
		(8 "In3.Cu" signal "GND1")
		(10 "In4.Cu" signal "IN2")
		(12 "In5.Cu" signal "VCC")
		(14 "In6.Cu" signal "VCC1")
		(16 "In7.Cu" signal "IN3")
		(18 "In8.Cu" signal "GND2")
		(20 "In9.Cu" signal "IN4")
		(22 "In10.Cu" signal "GND3")
		(2 "B.Cu" signal "BOTTOM")
		(9 "F.Adhes" user "F.Adhesive")
		(11 "B.Adhes" user "B.Adhesive")
		(13 "F.Paste" user "Package Geometry/Pastemask Top")
		(15 "B.Paste" user "Package Geometry/Pastemask Bottom")
		(5 "F.SilkS" user "Ref Des/Silkscreen Top")
		(7 "B.SilkS" user "Ref Des/Silkscreen Bottom")
		(1 "F.Mask" user "Board Geometry/Soldermask Top")
		(3 "B.Mask" user "Board Geometry/Soldermask Bottom")
		(17 "Dwgs.User" user "User.Drawings")
		(19 "Cmts.User" user "User.Comments")
		(21 "Eco1.User" user "User.Eco1")
		(23 "Eco2.User" user "User.Eco2")
		(25 "Edge.Cuts" user "Board Geometry/Outline")
		(27 "Margin" user)
		(31 "F.CrtYd" user "Package Geometry/Place Bound Top")
		(29 "B.CrtYd" user "Package Geometry/Place Bound Bottom")
		(35 "F.Fab" user "Ref Des/Assembly Top")
		(33 "B.Fab" user "Ref Des/Assembly Bottom")
	)
	(footprint ""
		(layer "F.Cu")
		(at 37.61232 -106.4895 180)
		(property "Reference" "R482"
			(at 0 0 180)
			(layer "F.SilkS")
			(hide yes)
			(effects
				(font
					(size 1.27 1.27)
				)
			)
		)
		(property "Value" ""
			(at 0 0 180)
			(layer "F.Fab")
			(effects
				(font
					(size 1.27 1.27)
				)
			)
		)
		(duplicate_pad_numbers_are_jumpers no)
		(fp_line
			(start 0.7874 0.4064)
			(end -0.7874 0.4064)
			(stroke
				(width 0.1524)
				(type default)
			)
			(layer "F.SilkS")
		)
		(fp_line
			(start 0.7874 -0.4064)
			(end 0.7874 0.4064)
			(stroke
				(width 0.1524)
				(type default)
			)
			(layer "F.SilkS")
		)
		(fp_line
			(start -0.7874 0.4064)
			(end -0.7874 -0.4064)
			(stroke
				(width 0.1524)
				(type default)
			)
			(layer "F.SilkS")
		)
		(fp_line
			(start -0.7874 -0.4064)
			(end 0.7874 -0.4064)
			(stroke
				(width 0.1524)
				(type default)
			)
			(layer "F.SilkS")
		)
		(fp_line
			(start 0.67945 0.3048)
			(end 0.120396 0.3048)
			(stroke
				(width 0.1)
				(type default)
			)
			(layer "F.Fab")
		)
		(fp_line
			(start 0.67945 -0.3048)
			(end 0.67945 0.3048)
			(stroke
				(width 0.1)
				(type default)
			)
			(layer "F.Fab")
		)
		(fp_line
			(start 0.12065 -0.2794)
			(end 0.12065 -0.3048)
			(stroke
				(width 0.1)
				(type default)
			)
			(layer "F.Fab")
		)
		(fp_line
			(start 0.12065 -0.3048)
			(end 0.67945 -0.3048)
			(stroke
				(width 0.1)
				(type default)
			)
			(layer "F.Fab")
		)
		(fp_line
			(start 0.120396 0.3048)
			(end 0.120396 0.2794)
			(stroke
				(width 0.1)
				(type default)
			)
			(layer "F.Fab")
		)
		(fp_line
			(start 0.120396 0.2794)
			(end -0.12065 0.2794)
			(stroke
				(width 0.1)
				(type default)
			)
			(layer "F.Fab")
		)
		(fp_line
			(start -0.12065 0.3048)
			(end -0.67945 0.3048)
			(stroke
				(width 0.1)
				(type default)
			)
			(layer "F.Fab")
		)
		(fp_line
			(start -0.12065 0.2794)
			(end -0.12065 0.3048)
			(stroke
				(width 0.1)
				(type default)
			)
			(layer "F.Fab")
		)
		(fp_line
			(start -0.12065 -0.2794)
			(end 0.12065 -0.2794)
			(stroke
				(width 0.1)
				(type default)
			)
			(layer "F.Fab")
		)
		(fp_line
			(start -0.12065 -0.305054)
			(end -0.12065 -0.2794)
			(stroke
				(width 0.1)
				(type default)
			)
			(layer "F.Fab")
		)
		(fp_line
			(start -0.67945 0.3048)
			(end -0.67945 -0.305054)
			(stroke
				(width 0.1)
				(type default)
			)
			(layer "F.Fab")
		)
		(fp_line
			(start -0.67945 -0.305054)
			(end -0.12065 -0.305054)
			(stroke
				(width 0.1)
				(type default)
			)
			(layer "F.Fab")
		)
		(pad "1" smd circle
			(at -0.40005 0 180)
			(size 0 0)
			(layers "F.Cu" "F.Mask" "F.Paste")
			(net "SPI_PCH_MUXED_IO0")
		)
		(pad "2" smd circle
			(at 0.40005 0 180)
			(size 0 0)
			(layers "F.Cu" "F.Mask" "F.Paste")
			(net "SPI_PCH_IO0_FLASH_R1")
		)
	)
	(footprint ""
		(layer "F.Cu")
		(at 16.002 -102.743 -90)
		(property "Reference" "R574"
			(at 0 0 270)
			(layer "F.SilkS")
			(hide yes)
			(effects
				(font
					(size 1.27 1.27)
				)
			)
		)
		(property "Value" ""
			(at 0 0 270)
			(layer "F.Fab")
			(effects
				(font
					(size 1.27 1.27)
				)
			)
		)
		(duplicate_pad_numbers_are_jumpers no)
		(fp_line
			(start -0.7874 0.4064)
			(end -0.7874 -0.4064)
			(stroke
				(width 0.1524)
				(type default)
			)
			(layer "F.SilkS")
		)
		(fp_line
			(start 0.7874 0.4064)
			(end -0.7874 0.4064)
			(stroke
				(width 0.1524)
				(type default)
			)
			(layer "F.SilkS")
		)
		(fp_line
			(start -0.7874 -0.4064)
			(end 0.7874 -0.4064)
			(stroke
				(width 0.1524)
				(type default)
			)
			(layer "F.SilkS")
		)
		(fp_line
			(start 0.7874 -0.4064)
			(end 0.7874 0.4064)
			(stroke
				(width 0.1524)
				(type default)
			)
			(layer "F.SilkS")
		)
		(fp_line
			(start -0.67945 0.3048)
			(end -0.67945 -0.305054)
			(stroke
				(width 0.1)
				(type default)
			)
			(layer "F.Fab")
		)
		(fp_line
			(start -0.12065 0.3048)
			(end -0.67945 0.3048)
			(stroke
				(width 0.1)
				(type default)
			)
			(layer "F.Fab")
		)
		(fp_line
			(start 0.120396 0.3048)
			(end 0.120396 0.2794)
			(stroke
				(width 0.1)
				(type default)
			)
			(layer "F.Fab")
		)
		(fp_line
			(start 0.67945 0.3048)
			(end 0.120396 0.3048)
			(stroke
				(width 0.1)
				(type default)
			)
			(layer "F.Fab")
		)
		(fp_line
			(start -0.12065 0.2794)
			(end -0.12065 0.3048)
			(stroke
				(width 0.1)
				(type default)
			)
			(layer "F.Fab")
		)
		(fp_line
			(start 0.120396 0.2794)
			(end -0.12065 0.2794)
			(stroke
				(width 0.1)
				(type default)
			)
			(layer "F.Fab")
		)
		(fp_line
			(start -0.12065 -0.2794)
			(end 0.12065 -0.2794)
			(stroke
				(width 0.1)
				(type default)
			)
			(layer "F.Fab")
		)
		(fp_line
			(start 0.12065 -0.2794)
			(end 0.12065 -0.3048)
			(stroke
				(width 0.1)
				(type default)
			)
			(layer "F.Fab")
		)
		(fp_line
			(start 0.12065 -0.3048)
			(end 0.67945 -0.3048)
			(stroke
				(width 0.1)
				(type default)
			)
			(layer "F.Fab")
		)
		(fp_line
			(start 0.67945 -0.3048)
			(end 0.67945 0.3048)
			(stroke
				(width 0.1)
				(type default)
			)
			(layer "F.Fab")
		)
		(fp_line
			(start -0.67945 -0.305054)
			(end -0.12065 -0.305054)
			(stroke
				(width 0.1)
				(type default)
			)
			(layer "F.Fab")
		)
		(fp_line
			(start -0.12065 -0.305054)
			(end -0.12065 -0.2794)
			(stroke
				(width 0.1)
				(type default)
			)
			(layer "F.Fab")
		)
		(pad "1" smd circle
			(at -0.40005 0 270)
			(size 0 0)
			(layers "F.Cu" "F.Mask" "F.Paste")
			(net "SMB_BMC_ALERT16_N")
		)
		(pad "2" smd circle
			(at 0.40005 0 270)
			(size 0 0)
			(layers "F.Cu" "F.Mask" "F.Paste")
			(net "SMB_BMC_ALERT16_R2_N")
		)
	)
)
